(kicad_pcb
	(version 20260206)
	(generator "pcbnew")
	(generator_version "10.0")
	(general
		(thickness 1.6)
		(legacy_teardrops no)
	)
	(paper "A4")
	(title_block
		(title "pdpb — Lightning_PDPB_BRD.brd")
		(comment 1 "Lightning (Wiwynn / Facebook NVMe JBOF) / footprints 218-221 of 1140")
	)
	(layers
		(0 "F.Cu" signal "TOP")
		(4 "In1.Cu" signal "L2GND")
		(6 "In2.Cu" signal "L3")
		(8 "In3.Cu" signal "L4VCC")
		(10 "In4.Cu" signal "L5VCC")
		(12 "In5.Cu" signal "L6")
		(14 "In6.Cu" signal "L7GND")
		(2 "B.Cu" signal "BOTTOM")
		(9 "F.Adhes" user "F.Adhesive")
		(11 "B.Adhes" user "B.Adhesive")
		(13 "F.Paste" user "Package Geometry/Pastemask Top")
		(15 "B.Paste" user "Package Geometry/Pastemask Bottom")
		(5 "F.SilkS" user "Ref Des/Silkscreen Top")
		(7 "B.SilkS" user "Ref Des/Silkscreen Bottom")
		(1 "F.Mask" user "Board Geometry/Soldermask Top")
		(3 "B.Mask" user "Board Geometry/Soldermask Bottom")
		(17 "Dwgs.User" user "User.Drawings")
		(19 "Cmts.User" user "User.Comments")
		(21 "Eco1.User" user "User.Eco1")
		(23 "Eco2.User" user "User.Eco2")
		(25 "Edge.Cuts" user "Board Geometry/Outline")
		(27 "Margin" user)
		(31 "F.CrtYd" user "Package Geometry/Place Bound Top")
		(29 "B.CrtYd" user "Package Geometry/Place Bound Bottom")
		(35 "F.Fab" user "Ref Des/Assembly Top")
		(33 "B.Fab" user "Ref Des/Assembly Bottom")
	)
	(footprint ""
		(layer "F.Cu")
		(at 86.487 -313.817 180)
		(property "Reference" "R9103"
			(at 0 0 180)
			(layer "F.SilkS")
			(hide yes)
			(effects
				(font
					(size 1.27 1.27)
				)
			)
		)
		(property "Value" "27R2F-GP"
			(at 0.064008 -3.993896 180)
			(unlocked yes)
			(layer "F.Fab")
			(hide yes)
			(effects
				(font
					(size 1.016 1.016)
					(thickness 0.1524)
				)
			)
		)
		(property "Device Type" "R402H16"
			(at 0.064008 -5.517896 180)
			(unlocked yes)
			(layer "F.Fab")
			(hide yes)
			(effects
				(font
					(size 1.016 1.016)
					(thickness 0.1524)
				)
			)
		)
		(duplicate_pad_numbers_are_jumpers no)
		(fp_line
			(start 0.508 -0.9398)
			(end -0.508 -0.9398)
			(stroke
				(width 0.1524)
				(type default)
			)
			(layer "F.SilkS")
		)
		(fp_line
			(start -0.508 -0.9398)
			(end -0.508 0.9398)
			(stroke
				(width 0.1524)
				(type default)
			)
			(layer "F.SilkS")
		)
		(fp_rect
			(start -0.508 0.9398)
			(end 0.508 -0.9398)
			(stroke
				(width 0)
				(type default)
			)
			(fill no)
			(layer "F.CrtYd")
		)
		(fp_rect
			(start -0.508 0.9398)
			(end 0.508 -0.9398)
			(stroke
				(width 0)
				(type default)
			)
			(fill no)
			(layer "F.Fab")
		)
		(pad "1" smd custom
			(at 0 -0.4445 180)
			(size 0.1397 0.1397)
			(layers "F.Cu" "F.Mask" "F.Paste")
			(net "PE_CLK_100M_DR11_1_R_N")
			(options
				(clearance outline)
				(anchor circle)
			)
			(primitives
				(gr_poly
					(pts
						(arc
							(start -0.1778 -0.2794)
							(mid -0.249642 -0.249642)
							(end -0.2794 -0.1778)
						)
						(arc
							(start -0.2794 0.1778)
							(mid -0.249642 0.249642)
							(end -0.1778 0.2794)
						)
						(arc
							(start 0.1778 0.2794)
							(mid 0.249642 0.249642)
							(end 0.2794 0.1778)
						)
						(arc
							(start 0.2794 -0.1778)
							(mid 0.249642 -0.249642)
							(end 0.1778 -0.2794)
						)
					)
					(width 0)
					(fill yes)
				)
			)
		)
		(pad "2" smd custom
			(at 0 0.4445 180)
			(size 0.1397 0.1397)
			(layers "F.Cu" "F.Mask" "F.Paste")
			(net "PE_CLK100M_DR11_1_N")
			(options
				(clearance outline)
				(anchor circle)
			)
			(primitives
				(gr_poly
					(pts
						(arc
							(start -0.1778 -0.2794)
							(mid -0.249642 -0.249642)
							(end -0.2794 -0.1778)
						)
						(arc
							(start -0.2794 0.1778)
							(mid -0.249642 0.249642)
							(end -0.1778 0.2794)
						)
						(arc
							(start 0.1778 0.2794)
							(mid 0.249642 0.249642)
							(end 0.2794 0.1778)
						)
						(arc
							(start 0.2794 -0.1778)
							(mid 0.249642 -0.249642)
							(end 0.1778 -0.2794)
						)
					)
					(width 0)
					(fill yes)
				)
			)
		)
	)
	(footprint ""
		(layer "F.Cu")
		(at 95.504 -110.236 180)
		(property "Reference" "R9132"
			(at 0 0 180)
			(layer "F.SilkS")
			(hide yes)
			(effects
				(font
					(size 1.27 1.27)
				)
			)
		)
		(property "Value" "27R2F-GP"
			(at 0.064008 -3.993896 180)
			(unlocked yes)
			(layer "F.Fab")
			(hide yes)
			(effects
				(font
					(size 1.016 1.016)
					(thickness 0.1524)
				)
			)
		)
		(property "Device Type" "R402H16"
			(at 0.064008 -5.517896 180)
			(unlocked yes)
			(layer "F.Fab")
			(hide yes)
			(effects
				(font
					(size 1.016 1.016)
					(thickness 0.1524)
				)
			)
		)
		(duplicate_pad_numbers_are_jumpers no)
		(fp_line
			(start 0.508 -0.9398)
			(end -0.508 -0.9398)
			(stroke
				(width 0.1524)
				(type default)
			)
			(layer "F.SilkS")
		)
		(fp_line
			(start -0.508 -0.9398)
			(end -0.508 0.9398)
			(stroke
				(width 0.1524)
				(type default)
			)
			(layer "F.SilkS")
		)
		(fp_rect
			(start -0.508 0.9398)
			(end 0.508 -0.9398)
			(stroke
				(width 0)
				(type default)
			)
			(fill no)
			(layer "F.CrtYd")
		)
		(fp_rect
			(start -0.508 0.9398)
			(end 0.508 -0.9398)
			(stroke
				(width 0)
				(type default)
			)
			(fill no)
			(layer "F.Fab")
		)
		(pad "1" smd custom
			(at 0 -0.4445 180)
			(size 0.1397 0.1397)
			(layers "F.Cu" "F.Mask" "F.Paste")
			(net "PE_CLK_100M_DR8_1_R_N")
			(options
				(clearance outline)
				(anchor circle)
			)
			(primitives
				(gr_poly
					(pts
						(arc
							(start -0.1778 -0.2794)
							(mid -0.249642 -0.249642)
							(end -0.2794 -0.1778)
						)
						(arc
							(start -0.2794 0.1778)
							(mid -0.249642 0.249642)
							(end -0.1778 0.2794)
						)
						(arc
							(start 0.1778 0.2794)
							(mid 0.249642 0.249642)
							(end 0.2794 0.1778)
						)
						(arc
							(start 0.2794 -0.1778)
							(mid 0.249642 -0.249642)
							(end 0.1778 -0.2794)
						)
					)
					(width 0)
					(fill yes)
				)
			)
		)
		(pad "2" smd custom
			(at 0 0.4445 180)
			(size 0.1397 0.1397)
			(layers "F.Cu" "F.Mask" "F.Paste")
			(net "PE_CLK100M_DR8_1_N")
			(options
				(clearance outline)
				(anchor circle)
			)
			(primitives
				(gr_poly
					(pts
						(arc
							(start -0.1778 -0.2794)
							(mid -0.249642 -0.249642)
							(end -0.2794 -0.1778)
						)
						(arc
							(start -0.2794 0.1778)
							(mid -0.249642 0.249642)
							(end -0.1778 0.2794)
						)
						(arc
							(start 0.1778 0.2794)
							(mid 0.249642 0.249642)
							(end 0.2794 0.1778)
						)
						(arc
							(start 0.2794 -0.1778)
							(mid 0.249642 -0.249642)
							(end 0.1778 -0.2794)
						)
					)
					(width 0)
					(fill yes)
				)
			)
		)
	)
	(footprint ""
		(layer "F.Cu")
		(at 26.416 -376.428)
		(property "Reference" "TP7"
			(at 0 0 0)
			(layer "F.SilkS")
			(hide yes)
			(effects
				(font
					(size 1.27 1.27)
				)
			)
		)
		(property "Value" "TPAD32-GP"
			(at -0.0508 -1.6764 0)
			(unlocked yes)
			(layer "F.Fab")
			(hide yes)
			(effects
				(font
					(size 1.016 1.016)
					(thickness 0.1524)
				)
			)
		)
		(property "Device Type" "TPAD32"
			(at -0.0508 -3.2004 0)
			(unlocked yes)
			(layer "F.Fab")
			(hide yes)
			(effects
				(font
					(size 1.016 1.016)
					(thickness 0.1524)
				)
			)
		)
		(duplicate_pad_numbers_are_jumpers no)
		(fp_poly
			(pts
				(arc
					(start 0.4064 0)
					(mid -0.4064 0)
					(end 0.4064 0)
				)
			)
			(stroke
				(width 0)
				(type default)
			)
			(fill no)
			(layer "F.CrtYd")
		)
		(fp_poly
			(pts
				(arc
					(start 0.7112 0)
					(mid -0.7112 0)
					(end 0.7112 0)
				)
			)
			(stroke
				(width 0)
				(type default)
			)
			(fill no)
			(layer "F.Fab")
		)
		(pad "1" smd circle
			(at 0 0)
			(size 0.8128 0.8128)
			(layers "F.Cu" "F.Mask" "F.Paste")
			(net "I2C_B_TMP4_ALERT")
		)
	)
	(footprint ""
		(layer "F.Cu")
		(at 206.67345 -404.94585 90)
		(property "Reference" "R9785"
			(at 0 0 90)
			(layer "F.SilkS")
			(hide yes)
			(effects
				(font
					(size 1.27 1.27)
				)
			)
		)
		(property "Value" "1KR2J-1-GP"
			(at 0.064008 -3.993896 90)
			(unlocked yes)
			(layer "F.Fab")
			(hide yes)
			(effects
				(font
					(size 1.016 1.016)
					(thickness 0.1524)
				)
			)
		)
		(property "Device Type" "R402H16"
			(at 0.064008 -5.517896 90)
			(unlocked yes)
			(layer "F.Fab")
			(hide yes)
			(effects
				(font
					(size 1.016 1.016)
					(thickness 0.1524)
				)
			)
		)
		(duplicate_pad_numbers_are_jumpers no)
		(fp_line
			(start 0.508 -0.9398)
			(end -0.508 -0.9398)
			(stroke
				(width 0.1524)
				(type default)
			)
			(layer "F.SilkS")
		)
		(fp_line
			(start -0.508 -0.9398)
			(end -0.508 0.9398)
			(stroke
				(width 0.1524)
				(type default)
			)
			(layer "F.SilkS")
		)
		(fp_rect
			(start -0.508 0.9398)
			(end 0.508 -0.9398)
			(stroke
				(width 0)
				(type default)
			)
			(fill no)
			(layer "F.CrtYd")
		)
		(fp_rect
			(start -0.508 0.9398)
			(end 0.508 -0.9398)
			(stroke
				(width 0)
				(type default)
			)
			(fill no)
			(layer "F.Fab")
		)
		(pad "1" smd custom
			(at 0 -0.4445 90)
			(size 0.1397 0.1397)
			(layers "F.Cu" "F.Mask" "F.Paste")
			(net "SSD1_PWREN")
			(options
				(clearance outline)
				(anchor circle)
			)
			(primitives
				(gr_poly
					(pts
						(arc
							(start -0.1778 -0.2794)
							(mid -0.249642 -0.249642)
							(end -0.2794 -0.1778)
						)
						(arc
							(start -0.2794 0.1778)
							(mid -0.249642 0.249642)
							(end -0.1778 0.2794)
						)
						(arc
							(start 0.1778 0.2794)
							(mid 0.249642 0.249642)
							(end 0.2794 0.1778)
						)
						(arc
							(start 0.2794 -0.1778)
							(mid 0.249642 -0.249642)
							(end 0.1778 -0.2794)
						)
					)
					(width 0)
					(fill yes)
				)
			)
		)
		(pad "2" smd custom
			(at 0 0.4445 90)
			(size 0.1397 0.1397)
			(layers "F.Cu" "F.Mask" "F.Paste")
			(net "SSD1_PWREN_R")
			(options
				(clearance outline)
				(anchor circle)
			)
			(primitives
				(gr_poly
					(pts
						(arc
							(start -0.1778 -0.2794)
							(mid -0.249642 -0.249642)
							(end -0.2794 -0.1778)
						)
						(arc
							(start -0.2794 0.1778)
							(mid -0.249642 0.249642)
							(end -0.1778 0.2794)
						)
						(arc
							(start 0.1778 0.2794)
							(mid 0.249642 0.249642)
							(end 0.2794 0.1778)
						)
						(arc
							(start 0.2794 -0.1778)
							(mid 0.249642 -0.249642)
							(end 0.1778 -0.2794)
						)
					)
					(width 0)
					(fill yes)
				)
			)
		)
	)
)
